# BASEBOARD_FAB2 (Tioga Pass) — schematic parts with pin connectivity, parts 4429–4567 of 4751; source: Cadence DE-HDL packaged netlist (pstxprt.dat, pstxnet.dat, pstchip.dat)

R25W183  374R2F-1-GP  1%  pkg SMD-RG  page 255 : 1 = P3V3_STBY ; 2 = P0V7_GTL2014_VREF_6
R25W184  RES  0.0 5% CHIP  pkg 0402  page 146 : 1 = RST_BMC_PLTRST_BUF_N ; 2 = RST_PLTRST_BUF_N
R25W185  RES  4.75K 1% CHIP  pkg 0402  page 255 : 1 = P3V3_STBY ; 2 = BMC_JTAG_SEL
R25W186  RES  0.0 5% CHIP  pkg 0402  page 189 : 1 = BMC_JTAG_SEL_N ; 2 = FM_JTAG_PLD_EN_DEBUG
R25W187  RES  0.0 5% CHIP  pkg 0402  page 255 : 1 = JTAG_BMC_BUF_TDO_R ; 2 = JTAG_BMC_BUF_TDO
R30W1  RES  0.0 5% CHIP  pkg 0402  page 253 : 1 = USB3_P01_RXN ; 2 = USB3_P01_FB_RXN
R30W2  RES  0.0 5% CHIP  pkg 0402  page 253 : 1 = USB3_P01_RXP ; 2 = USB3_P01_FB_RXP
R30W3  RES  0.0 5% CHIP  pkg 0402  page 253 : 1 = USB3_P01_C_TXN ; 2 = USB3_P01_FB_TXN
R30W4  RES  0.0 5% CHIP  pkg 0402  page 253 : 1 = USB3_P01_C_TXP ; 2 = USB3_P01_FB_TXP
R32W1  RES  4.02K 1% CHIP  pkg 0402  page 185 : 1 = P3V3 ; 2 = P1V8_M2
R32W2  RES  1.5K 1% CHIP  pkg 0402  page 185 : 1 = P1V8_M2 ; 2 = VREF_LMV431_1V42
R32W3  RES  3.3K 5% CHIP  pkg 0402  page 185 : 1 = VREF_LMV431_1V42 ; 2 = GND
R32W4  RES  49.9K 1% CHIP  pkg 0402  page 185 : 1 = P1V8_M2 ; 2 = GND
R32W5  RES  2.0K 1% CHIP  pkg 0402  page 185 : 1 = P1V8_M2 ; 2 = SMB_M2_SCL
R32W6  RES  2.0K 1% CHIP  pkg 0402  page 185 : 1 = P1V8_M2 ; 2 = SMB_M2_SDA
R32W7  RES  2.0K 1% CHIP  pkg 0402  page 185 : 1 = P1V8_M2 ; 2 = SMB_M2_ALT_N
R32W9  RES  10.0K 1% CHIP  pkg 0402  page 185 : 1 = PD_SMB_M2_EN ; 2 = GND
R32W10  RES  0.0 5% CHIP  pkg 0402  page 185 : 1 = SMB_M2_SCL ; 2 = SMB_M2_SCL_R
R32W11  RES  0.0 5% CHIP  pkg 0402  page 185 : 1 = SMB_M2_SDA ; 2 = SMB_M2_SDA_R
R32W12  RES  0.0 5% CHIP  pkg 0402  page 185 : 1 = SMB_M2_ALT_N ; 2 = SMB_M2_ALT_R_N
R760  RES  0.0 5% CHIP  pkg 0402  page 244 : 1 = P3E_CPU0_PE1_PCH_RXN<15> ; 2 = P3E_CPU0_PE1_PCH_CON_RXN<15>
R767  RES  0.0 5% CHIP  pkg 0402  page 244 : 1 = P3E_CPU0_PE1_PCH_RXP<15> ; 2 = P3E_CPU0_PE1_PCH_CON_RXP<15>
R768  RES  0.0 5% CHIP  pkg 0402  page 244 : 1 = P3E_CPU0_PE1_PCH_RXN<14> ; 2 = P3E_CPU0_PE1_PCH_CON_RXN<14>
R769  RES  0.0 5% CHIP  pkg 0402  page 244 : 1 = P3E_CPU0_PE1_PCH_RXP<14> ; 2 = P3E_CPU0_PE1_PCH_CON_RXP<14>
R771  RES  0.0 5% CHIP  pkg 0402  page 244 : 1 = P3E_CPU0_PE1_PCH_RXN<13> ; 2 = P3E_CPU0_PE1_PCH_CON_RXN<13>
R774  RES  0.0 5% CHIP  pkg 0402  page 244 : 1 = P3E_CPU0_PE1_PCH_RXP<13> ; 2 = P3E_CPU0_PE1_PCH_CON_RXP<13>
R775  RES  0.0 5% CHIP  pkg 0402  page 244 : 1 = P3E_CPU0_PE1_PCH_RXN<12> ; 2 = P3E_CPU0_PE1_PCH_CON_RXN<12>
R777  RES  0.0 5% CHIP  pkg 0402  page 244 : 1 = P3E_CPU0_PE1_PCH_RXP<12> ; 2 = P3E_CPU0_PE1_PCH_CON_RXP<12>
R778  RES  0.0 5% CHIP  pkg 0402  page 244 : 1 = P3E_CPU0_PE1_PCH_RXN<11> ; 2 = P3E_CPU0_PE1_PCH_CON_RXN<11>
R779  RES  0.0 5% CHIP  pkg 0402  page 244 : 1 = P3E_CPU0_PE1_PCH_RXP<11> ; 2 = P3E_CPU0_PE1_PCH_CON_RXP<11>
R780  RES  0.0 5% CHIP  pkg 0402  page 244 : 1 = P3E_CPU0_PE1_PCH_RXN<10> ; 2 = P3E_CPU0_PE1_PCH_CON_RXN<10>
R781  RES  0.0 5% CHIP  pkg 0402  page 244 : 1 = P3E_CPU0_PE1_PCH_RXP<10> ; 2 = P3E_CPU0_PE1_PCH_CON_RXP<10>
R782  RES  0.0 5% CHIP  pkg 0402  page 244 : 1 = P3E_CPU0_PE1_PCH_RXN<9> ; 2 = P3E_CPU0_PE1_PCH_CON_RXN<9>
R783  RES  0.0 5% CHIP  pkg 0402  page 244 : 1 = P3E_CPU0_PE1_PCH_RXP<9> ; 2 = P3E_CPU0_PE1_PCH_CON_RXP<9>
R784  RES  0.0 5% CHIP  pkg 0402  page 244 : 1 = P3E_CPU0_PE1_PCH_RXN<8> ; 2 = P3E_CPU0_PE1_PCH_CON_RXN<8>
R785  RES  0.0 5% CHIP  pkg 0402  page 244 : 1 = P3E_CPU0_PE1_PCH_RXP<8> ; 2 = P3E_CPU0_PE1_PCH_CON_RXP<8>
RF1  RES  1.0K 0.1% CHIP  pkg 0402  page 201 : 1 = VR_PVCCIN_CPU0_AIREF1 ; 2 = ISENSE_PVCCIN_CPU0_PH1_IMON
RF2  RES  1.0K 0.1% CHIP  pkg 0402  page 201 : 1 = VR_PVCCIN_CPU0_AIREF2 ; 2 = ISENSE_PVCCIN_CPU0_PH2_IMON
RF3  RES  1.0K 0.1% CHIP  pkg 0402  page 201 : 1 = VR_PVCCIN_CPU0_AIREF3 ; 2 = ISENSE_PVCCIN_CPU0_PH3_IMON
RF4  RES  1.0K 0.1% CHIP  pkg 0402  page 201 : 1 = VR_PVCCIN_CPU0_AIREF4 ; 2 = ISENSE_PVCCIN_CPU0_PH4_IMON
RF5  RES  1.0K 0.1% CHIP  pkg 0402  page 201 : 1 = VR_PVCCIN_CPU0_AIREF5 ; 2 = ISENSE_PVCCIN_CPU0_PH5_IMON
RF6  RES  1.0K 0.1% CHIP  pkg 0402  page 201 : 1 = VR_PVSA_CPU0_BIREF1 ; 2 = ISENSE_PVSA_CPU0_IMON
RF7  RES  1.0K 0.1% CHIP  pkg 0402  page 206 : 1 = VR_PVCCIN_CPU1_AIREF1 ; 2 = ISENSE_PVCCIN_CPU1_PH1_IMON
RF8  RES  1.0K 0.1% CHIP  pkg 0402  page 206 : 1 = VR_PVCCIN_CPU1_AIREF2 ; 2 = ISENSE_PVCCIN_CPU1_PH2_IMON
RF9  RES  1.0K 0.1% CHIP  pkg 0402  page 206 : 1 = VR_PVCCIN_CPU1_AIREF3 ; 2 = ISENSE_PVCCIN_CPU1_PH3_IMON
RF10  RES  1.0K 0.1% CHIP  pkg 0402  page 206 : 1 = VR_PVCCIN_CPU1_AIREF4 ; 2 = ISENSE_PVCCIN_CPU1_PH4_IMON
RF11  RES  1.0K 0.1% CHIP  pkg 0402  page 206 : 1 = VR_PVCCIN_CPU1_AIREF5 ; 2 = ISENSE_PVCCIN_CPU1_PH5_IMON
RF12  RES  1.0K 0.1% CHIP  pkg 0402  page 206 : 1 = VR_PVSA_CPU1_BIREF1 ; 2 = ISENSE_PVSA_CPU1_IMON
RF13  RES  1.0K 0.1% CHIP  pkg 0402  page 211 : 1 = VR_PVCCIO_CPU0_AIREF1 ; 2 = ISENSE_PVCCIO_CPU0_PH1_IMON
RF14  RES  1.0K 0.1% CHIP  pkg 0402  page 213 : 1 = VR_PVCCIO_CPU1_AIREF1 ; 2 = ISENSE_PVCCIO_CPU1_PH1_IMON
RF15  RES  1.0K 0.1% CHIP  pkg 0402  page 215 : 1 = VR_PVDDQ_ABC_AIREF1 ; 2 = ISENSE_PVDDQ_ABC_PH1_IMON
RF16  RES  1.0K 0.1% CHIP  pkg 0402  page 215 : 1 = VR_PVDDQ_ABC_AIREF2 ; 2 = ISENSE_PVDDQ_ABC_PH2_IMON
RF17  RES  1.0K 0.1% CHIP  pkg 0402  page 218 : 1 = VR_PVDDQ_DEF_AIREF1 ; 2 = ISENSE_PVDDQ_DEF_PH1_IMON
RF18  RES  1.0K 0.1% CHIP  pkg 0402  page 218 : 1 = VR_PVDDQ_DEF_AIREF2 ; 2 = ISENSE_PVDDQ_DEF_PH2_IMON
RF19  RES  1.0K 0.1% CHIP  pkg 0402  page 223 : 1 = VR_PVDDQ_GHJ_AIREF1 ; 2 = ISENSE_PVDDQ_GHJ_PH1_IMON
RF20  RES  1.0K 0.1% CHIP  pkg 0402  page 223 : 1 = VR_PVDDQ_GHJ_AIREF2 ; 2 = ISENSE_PVDDQ_GHJ_PH2_IMON
RF21  RES  1.0K 0.1% CHIP  pkg 0402  page 226 : 1 = VR_PVDDQ_KLM_AIREF1 ; 2 = ISENSE_PVDDQ_KLM_PH1_IMON
RF22  RES  1.0K 0.1% CHIP  pkg 0402  page 226 : 1 = VR_PVDDQ_KLM_AIREF2 ; 2 = ISENSE_PVDDQ_KLM_PH2_IMON
RF23  RES  1.0K 0.1% CHIP  pkg 0402  page 235 : 1 = VR_PVNN_PCH_AIREF1 ; 2 = ISENSE_PVNN_PCH_PH1_IMON
RF24  RES  1.0K 0.1% CHIP  pkg 0402  page 235 : 1 = VR_P1V05_PCH_BIREF1 ; 2 = ISENSE_P1V05_PCH_STBY_PH1_IMON

RM1E1  CONN3_G98259001  CONN  pkg PIP  page 195
  1  IO1  BI  = GND
  2  IO2  BI  = GND
  3  IO3  BI  = GND

RM1G1  STFT363B238R224H453-GP  pkg DISCRET-GC1  page 195 : 1 = GND
RM8D1  STANDOFF  SO  pkg TH1  page 184 : 1 = GND
RN8F1  RES  4.75K 1% CHIP  pkg 0402  page 137 : 1 = P3V3_STBY ; 2 = PU_SPI_BMC_BT_CS0_N
RN8F2  RES  4.75K 1% EMPTY  pkg 0402  page 246 : 1 = P3V3_STBY ; 2 = TPM_SPI_BMC_WP_N
RN8F3  RES  4.75K 1% CHIP  pkg 0402  page 246 : 1 = P3V3_STBY ; 2 = PU_TPM_SPI_BMC_HOLD_N
RN8F4  RES  4.75K 1% EMPTY  pkg 0402  page 246 : 1 = P3V3_STBY ; 2 = PU_TPM_SPI_FLASH_RESET_2_N
RN8F5  RES  33.2 1% CHIP  pkg 0402  page 246 : 1 = SPI_BMC_BT_DI ; 2 = SPI_TPM_BMC_DI_R
RN8F6  82KR2F-1-GP  1%  pkg SMD-RG  page 246 : 1 = TPM_SPI_BMC_WP_N ; 2 = GND
RT1  RES  0 5.0% CHIP  pkg 0603  page 202 : 1 = VR_PVCCIN_CPU0_PH1_BOOT ; 2 = VR_PVCCIN_CPU0_PH1_BOOT_R
RT2  1R3F-GP  1%  pkg RCL_GP  page 202 : 1 = VR_PVCCIN_CPU0_PHASE1_RC ; 2 = GND
RT3  RES  0 5.0% CHIP  pkg 0603  page 202 : 1 = VR_PVCCIN_CPU0_PH2_BOOT ; 2 = VR_PVCCIN_CPU0_PH2_BOOT_R
RT4  1R3F-GP  1%  pkg RCL_GP  page 202 : 1 = VR_PVCCIN_CPU0_PHASE2_RC ; 2 = GND
RT5  RES  0 5.0% CHIP  pkg 0603  page 227 : 1 = VR_PVDDQ_KLM_PH1_BOOT ; 2 = VR_PVDDQ_KLM_PH1_BOOT_R
RT6  1R3F-GP  1%  pkg RCL_GP  page 227 : 1 = VR_PVDDQ_KLM_PH1_RC ; 2 = GND
RT7  1R3F-GP  1%  pkg RCL_GP  page 227 : 1 = VR_PVDDQ_KLM_PH2_RC ; 2 = GND
RT8  RES  0 5.0% CHIP  pkg 0603  page 227 : 1 = VR_PVDDQ_KLM_PH2_BOOT ; 2 = VR_PVDDQ_KLM_PH2_BOOT_R
RT8P1  RES  100.0K 1% CHIP  pkg 0603  page 71 : 1 = PVCCIN_CPU1 ; 2 = VSENSE_VCCINR2PMAX_CPU1
RT9  RES  0 5.0% CHIP  pkg 0603  page 209 : 1 = VR_PVCCIN_CPU1_PH5_BOOT ; 2 = VR_PVCCIN_CPU1_PH5_BOOT_R
RT10  1R3F-GP  1%  pkg RCL_GP  page 209 : 1 = VR_PVCCIN_CPU1_PHASE5_RC ; 2 = GND
RT11  RES  0 5.0% CHIP  pkg 0603  page 208 : 1 = VR_PVCCIN_CPU1_PH3_BOOT ; 2 = VR_PVCCIN_CPU1_PH3_BOOT_R
RT12  1R3F-GP  1%  pkg RCL_GP  page 208 : 1 = VR_PVCCIN_CPU1_PHASE3_RC ; 2 = GND
RT13  1R3F-GP  1%  pkg RCL_GP  page 208 : 1 = VR_PVCCIN_CPU1_PHASE4_RC ; 2 = GND
RT14  RES  0 5.0% CHIP  pkg 0603  page 208 : 1 = VR_PVCCIN_CPU1_PH4_BOOT ; 2 = VR_PVCCIN_CPU1_PH4_BOOT_R
RT15  RES  0 5.0% CHIP  pkg 0603  page 207 : 1 = VR_PVCCIN_CPU1_PH1_BOOT ; 2 = VR_PVCCIN_CPU1_PH1_BOOT_R
RT16  1R3F-GP  1%  pkg RCL_GP  page 207 : 1 = VR_PVCCIN_CPU1_PHASE1_RC ; 2 = GND
RT17  RES  0 5.0% CHIP  pkg 0603  page 207 : 1 = VR_PVCCIN_CPU1_PH2_BOOT ; 2 = VR_PVCCIN_CPU1_PH2_BOOT_R
RT18  1R3F-GP  1%  pkg RCL_GP  page 207 : 1 = VR_PVCCIN_CPU1_PHASE2_RC ; 2 = GND
RT19  RES  0 5.0% CHIP  pkg 0603  page 224 : 1 = VR_PVDDQ_GHJ_PH1_BOOT ; 2 = VR_PVDDQ_GHJ_PH1_BOOT_R
RT20  1R3F-GP  1%  pkg RCL_GP  page 224 : 1 = VR_PVDDQ_GHJ_PH1_SW_RC ; 2 = GND
RT21  RES  0 5.0% CHIP  pkg 0603  page 224 : 1 = VR_PVDDQ_GHJ_PH2_BOOT ; 2 = VR_PVDDQ_GHJ_PH2_BOOT_R
RT22  1R3F-GP  1%  pkg RCL_GP  page 224 : 1 = VR_PVDDQ_GHJ_PH2_SW_RC ; 2 = GND
RT23  RES  0 5.0% CHIP  pkg 0603  page 204 : 1 = VR_PVCCIN_CPU0_PH5_BOOT ; 2 = VR_PVCCIN_CPU0_PH5_BOOT_R
RT24  1R3F-GP  1%  pkg RCL_GP  page 204 : 1 = VR_PVCCIN_CPU0_PHASE5_RC ; 2 = GND
RT25  RES  0 5.0% CHIP  pkg 0603  page 203 : 1 = VR_PVCCIN_CPU0_PH3_BOOT ; 2 = VR_PVCCIN_CPU0_PH3_BOOT_R
RT26  1R3F-GP  1%  pkg RCL_GP  page 203 : 1 = VR_PVCCIN_CPU0_PHASE3_RC ; 2 = GND
RT27  1R3F-GP  1%  pkg RCL_GP  page 203 : 1 = VR_PVCCIN_CPU0_PHASE4_RC ; 2 = GND
RT28  RES  0 5.0% CHIP  pkg 0603  page 203 : 1 = VR_PVCCIN_CPU0_PH4_BOOT ; 2 = VR_PVCCIN_CPU0_PH4_BOOT_R
RT29  1R3F-GP  1%  pkg RCL_GP  page 219 : 1 = VR_PVDDQ_DEF_PH1_SW_RC ; 2 = GND
RT30  RES  0 5.0% CHIP  pkg 0603  page 219 : 1 = VR_PVDDQ_DEF_PH1_BOOT ; 2 = VR_PVDDQ_DEF_PH1_BOOT_R
RT31  RES  0 5.0% CHIP  pkg 0603  page 219 : 1 = VR_PVDDQ_DEF_PH2_BOOT ; 2 = VR_PVDDQ_DEF_PH2_BOOT_R
RT32  1R3F-GP  1%  pkg RCL_GP  page 219 : 1 = VR_PVDDQ_DEF_PH2_SW_RC ; 2 = GND
RT33  RES  0 5.0% CHIP  pkg 0603  page 216 : 1 = VR_PVDDQ_ABC_PH1_BOOT ; 2 = VR_PVDDQ_ABC_PH1_BOOT_R
RT34  1R3F-GP  1%  pkg RCL_GP  page 216 : 1 = VR_PVDDQ_ABC_PH1_SW_RC ; 2 = GND
RT35  1R3F-GP  1%  pkg RCL_GP  page 216 : 1 = VR_PVDDQ_ABC_PH2_SW_RC ; 2 = GND
RT36  RES  0 5.0% CHIP  pkg 0603  page 216 : 1 = VR_PVDDQ_ABC_PH2_BOOT ; 2 = VR_PVDDQ_ABC_PH2_BOOT_R
RT37  RES  0 5.0% CHIP  pkg 0603  page 210 : 1 = VR_PVSA_CPU1_BOOT ; 2 = VR_PVSA_CPU1_BOOT_R
RT38  1R3F-GP  1%  pkg RCL_GP  page 210 : 1 = VR_PVSA_CPU1_PHASE_SW_RC ; 2 = GND
RT39  1R3F-GP  1%  pkg RCL_GP  page 205 : 1 = VR_PVSA_CPU0_PHASE_SW_RC ; 2 = GND
RT40  RES  0 5.0% CHIP  pkg 0603  page 205 : 1 = VR_PVSA_CPU0_BOOT ; 2 = VR_PVSA_CPU0_BOOT_R
RT41  RES  0 5.0% CHIP  pkg 0603  page 214 : 1 = VR_PVCCIO_CPU1_PH1_BOOT ; 2 = VR_PVCCIO_CPU1_PH1_BOOT_R
RT42  1R3F-GP  1%  pkg RCL_GP  page 214 : 1 = VR_PVCCIO_CPU1_PH1_SW_RC ; 2 = GND
RT43  1R3F-GP  1%  pkg RCL_GP  page 236 : 1 = VR_PVNN_PCH_PH1_PHASE_SW_RC ; 2 = GND
RT44  RES  0 5.0% CHIP  pkg 0603  page 236 : 1 = VR_PVNN_PCH_PH1_BOOT ; 2 = VR_PVNN_PCH_PH1_BOOT_R
RT45  1R3F-GP  1%  pkg RCL_GP  page 236 : 1 = VR_P1V05_PCH_STBY_PH1_SW_RC ; 2 = GND
RT46  RES  0 5.0% CHIP  pkg 0603  page 236 : 1 = VR_P1V05_PCH_STBY_PH1_BOOT ; 2 = VR_P1V05_PCH_STBY_PH1_BOOT_R
RT47  RES  0 5.0% CHIP  pkg 0603  page 212 : 1 = VR_PVCCIO_CPU0_PH1_BOOT ; 2 = VR_PVCCIO_CPU0_PH1_BOOT_R
RT48  1R3F-GP  1%  pkg RCL_GP  page 212 : 1 = VR_PVCCIO_CPU0_PH1_SW_RC ; 2 = GND
S8E1  SWITCH_D90553001  IC  pkg SMLF  page 157 : 1 = GND ; 2 = FP_NMI_BTN_OUT_R_N

S9A1  SWITCH_D37771002  IC  pkg SM  page 175
  1  PIN1  UNSPEC  = FM_DEBUG_RST_BTN_N
  2  PIN2  UNSPEC  = FM_DEBUG_RST_BTN_N
  3  PIN3  UNSPEC  = GND
  4  PIN4  UNSPEC  = GND

S9A2  SWITCH_D37771002  IC  pkg SM  page 175
  1  PIN1  UNSPEC  = GND
  2  PIN2  UNSPEC  = GND
  3  PIN3  UNSPEC  = FP_PWR_BTN_R_N
  4  PIN4  UNSPEC  = FP_PWR_BTN_R_N

S9W1  SW-SLIDE75-GP  pkg DISCRET-G6  page 255
  1  \1\  UNSPEC  = NC
  2  \2\  UNSPEC  = BMC_JTAG_SEL
  3  \3\  UNSPEC  = GND
  4  \4\  UNSPEC  = GND
  5  \5\  UNSPEC  = GND
  6  \6\  UNSPEC  = GND
  7  \7\  UNSPEC  = GND
  NP1  NP1  UNSPEC  = NC
  NP2  NP2  UNSPEC  = NC

SH3D1  SHUNT  EMPTY  pkg SH0201  page 214 : 1 = VSENSE_PVCCIO_CPU1_SKT_VRTN ; 2 = VSENSE_PVCCIO_CPU1_AVSN
SH3D2  SHUNT  EMPTY  pkg SH0201  page 214 : 1 = VSENSE_PVCCIO_CPU1_SKT_VSEN ; 2 = VSENSE_PVCCIO_CPU1_AVSP
SH3P1  SHUNT  EMPTY  pkg SH0201  page 212 : 1 = VSENSE_PVCCIO_CPU0_SKT_VSEN ; 2 = VSENSE_PVCCIO_CPU0_AVSP
SH3P2  SHUNT  EMPTY  pkg SH0201  page 212 : 1 = VSENSE_PVCCIO_CPU0_SKT_VRTN ; 2 = VSENSE_PVCCIO_CPU0_AVSN
SH4L1  SHUNT  EMPTY  pkg SH0201  page 220 : 1 = VSENSE_PVDDQ_DEF_N ; 2 = GND
SH4L2  SHUNT  EMPTY  pkg SH0201  page 220 : 1 = VSENSE_PVDDQ_DEF_P ; 2 = PVDDQ_DEF
SH4U1  SHUNT  EMPTY  pkg SH0201  page 217 : 1 = VSENSE_PVDDQ_ABC_N ; 2 = GND
SH4U2  SHUNT  EMPTY  pkg SH0201  page 217 : 1 = VSENSE_PVDDQ_ABC_P ; 2 = PVDDQ_ABC
SH5L1  SHUNT  EMPTY  pkg SH0201  page 222 : 1 = VR_PVTT_DEF_SNS ; 2 = PVTT_DEF
SH5U1  SHUNT  EMPTY  pkg SH0201  page 221 : 1 = VR_PVTT_ABC_SNS ; 2 = PVTT_ABC
SH7L1  SHUNT  EMPTY  pkg SH0201  page 228 : 1 = VSENSE_PVDDQ_KLM_N ; 2 = GND
SH7L2  SHUNT  EMPTY  pkg SH0201  page 228 : 1 = VSENSE_PVDDQ_KLM_P ; 2 = PVDDQ_KLM
SH7U1  SHUNT  EMPTY  pkg SH0201  page 225 : 1 = VSENSE_PVDDQ_GHJ_P ; 2 = PVDDQ_GHJ
SH7U2  SHUNT  EMPTY  pkg SH0201  page 225 : 1 = VSENSE_PVDDQ_GHJ_N ; 2 = GND
SH8L1  SHUNT  EMPTY  pkg SH0201  page 230 : 1 = VR_PVTT_KLM_SNS ; 2 = PVTT_KLM
SH8U1  SHUNT  EMPTY  pkg SH0201  page 229 : 1 = VR_PVTT_GHJ_SNS ; 2 = PVTT_GHJ

T1D1  TEST-PAD-12P-1-GP-U  pkg DISCRET-GB1  page 257
  1  DP  UNSPEC  = L1_85OHM_5INCH_DP
  2  DN  UNSPEC  = L1_85OHM_5INCH_DN
  3  GND(0)  POWER  = GND
  4  GND(1)  POWER  = GND
  5  GND(2)  POWER  = GND
  6  GND(3)  POWER  = GND
  7  GND(4)  POWER  = GND
  8  GND(5)  POWER  = GND
  9  GND(6)  POWER  = GND
  10  GND(7)  POWER  = GND
  11  GND(8)  POWER  = GND
  12  GND(9)  POWER  = GND
